(kicad_pcb
	(version 20241229)
	(generator "pcbnew")
	(generator_version "9.0")
	(general
		(thickness 1.61)
		(legacy_teardrops no)
	)
	(paper "A3")
	(title_block
		(title "SO-DIMM DDR5 Tester")
		(date "2025-11-26")
		(rev "1.3.0")
		(comment 9 "footprints 228-234 of 627")
	)
	(layers
		(0 "F.Cu" signal)
		(4 "In1.Cu" power)
		(6 "In2.Cu" mixed)
		(8 "In3.Cu" power)
		(10 "In4.Cu" mixed)
		(12 "In5.Cu" power)
		(14 "In6.Cu" mixed)
		(16 "In7.Cu" power)
		(18 "In8.Cu" power)
		(20 "In9.Cu" mixed)
		(22 "In10.Cu" power)
		(2 "B.Cu" signal)
		(9 "F.Adhes" user "F.Adhesive")
		(11 "B.Adhes" user "B.Adhesive")
		(13 "F.Paste" user)
		(15 "B.Paste" user)
		(5 "F.SilkS" user "F.Silkscreen")
		(7 "B.SilkS" user "B.Silkscreen")
		(1 "F.Mask" user)
		(3 "B.Mask" user)
		(17 "Dwgs.User" user "User.Drawings")
		(19 "Cmts.User" user "User.Comments")
		(21 "Eco1.User" user "User.Eco1")
		(23 "Eco2.User" user "User.Eco2")
		(25 "Edge.Cuts" user)
		(27 "Margin" user)
		(31 "F.CrtYd" user "F.Courtyard")
		(29 "B.CrtYd" user "B.Courtyard")
		(35 "F.Fab" user)
		(33 "B.Fab" user)
	)
	(footprint "antmicro-footprints:C_0402_1005Metric"
		(layer "F.Cu")
		(at 181.566 155.074999)
		(descr "Capacitor SMD 0402")
		(tags "capacitor SMD 0402")
		(property "Reference" "C216"
			(at 0 -0.699 0)
			(layer "F.SilkS")
			(hide yes)
			(effects
				(font
					(size 0.7 0.7)
					(thickness 0.15)
				)
				(justify left bottom)
			)
		)
		(property "Value" "C_100n_0402"
			(at -1.022927 2.155213 0)
			(layer "F.Fab")
			(effects
				(font
					(size 0.7 0.7)
					(thickness 0.15)
				)
				(justify left bottom)
			)
		)
		(property "Datasheet" "https://www.murata.com/products/productdetail?partno=GRM155R61H104KE14%23"
			(at 0 0 0)
			(layer "F.Fab")
			(hide yes)
			(effects
				(font
					(size 1.27 1.27)
					(thickness 0.15)
				)
			)
		)
		(property "Author" "Antmicro"
			(at 0 0 0)
			(layer "F.Fab")
			(hide yes)
			(effects
				(font
					(size 1 1)
					(thickness 0.15)
				)
			)
		)
		(property "Dielectric" "X5R"
			(at 0 0 0)
			(layer "F.Fab")
			(hide yes)
			(effects
				(font
					(size 1 1)
					(thickness 0.15)
				)
			)
		)
		(property "License" "Apache-2.0"
			(at 0 0 0)
			(layer "F.Fab")
			(hide yes)
			(effects
				(font
					(size 1 1)
					(thickness 0.15)
				)
			)
		)
		(property "MPN" "GRM155R61H104KE14D"
			(at 0 0 0)
			(layer "F.Fab")
			(hide yes)
			(effects
				(font
					(size 1 1)
					(thickness 0.15)
				)
			)
		)
		(property "Manufacturer" "Murata"
			(at 0 0 0)
			(layer "F.Fab")
			(hide yes)
			(effects
				(font
					(size 1 1)
					(thickness 0.15)
				)
			)
		)
		(property "Val" "100n"
			(at 0 0 0)
			(layer "F.Fab")
			(hide yes)
			(effects
				(font
					(size 1 1)
					(thickness 0.15)
				)
			)
		)
		(property "Voltage" "50V"
			(at 0 0 0)
			(layer "F.Fab")
			(hide yes)
			(effects
				(font
					(size 1 1)
					(thickness 0.15)
				)
			)
		)
		(sheetname "/Supply/")
		(sheetfile "supply.kicad_sch")
		(attr smd)
		(fp_rect
			(start -0.9659 -0.481258)
			(end 0.9649 0.458742)
			(stroke
				(width 0.05)
				(type solid)
			)
			(fill no)
			(layer "F.CrtYd")
		)
		(fp_line
			(start -0.499 -0.25)
			(end 0.499 -0.25)
			(stroke
				(width 0.15)
				(type solid)
			)
			(layer "F.Fab")
		)
		(fp_line
			(start -0.499 0.248)
			(end -0.499 -0.25)
			(stroke
				(width 0.15)
				(type solid)
			)
			(layer "F.Fab")
		)
		(fp_line
			(start 0.499 -0.25)
			(end 0.499 0.248)
			(stroke
				(width 0.15)
				(type solid)
			)
			(layer "F.Fab")
		)
		(fp_line
			(start 0.499 0.248)
			(end -0.499 0.248)
			(stroke
				(width 0.15)
				(type solid)
			)
			(layer "F.Fab")
		)
		(pad "1" smd roundrect
			(at -0.484 0)
			(size 0.59 0.64)
			(layers "F.Cu" "F.Mask" "F.Paste")
			(roundrect_rratio 0.25)
			(net 1 "GND")
			(pintype "passive")
		)
		(pad "2" smd roundrect
			(at 0.484 0)
			(size 0.59 0.64)
			(layers "F.Cu" "F.Mask" "F.Paste")
			(roundrect_rratio 0.25)
			(net 206 "+1V1")
			(pintype "passive")
		)
	)
	(footprint "antmicro-footprints:R_1206_3216Metric"
		(layer "F.Cu")
		(at 188.675 179.499 180)
		(property "Reference" "R142"
			(at 0.475 -1.951 180)
			(layer "F.SilkS")
			(effects
				(font
					(size 0.7 0.7)
					(thickness 0.15)
				)
				(justify left bottom)
			)
		)
		(property "Value" "R_0R01_1206"
			(at -2.422356 2.103591 180)
			(layer "F.Fab")
			(effects
				(font
					(size 0.7 0.7)
					(thickness 0.15)
				)
				(justify left bottom)
			)
		)
		(property "Datasheet" "https://www.yageo.com/upload/media/product/productsearch/datasheet/rchip/PYu-RL_Group_521_RoHS_L_2.pdf"
			(at 0 0 180)
			(layer "F.Fab")
			(hide yes)
			(effects
				(font
					(size 1.27 1.27)
					(thickness 0.15)
				)
			)
		)
		(property "Author" "Antmicro"
			(at 377.35 358.998 0)
			(layer "F.Fab")
			(hide yes)
			(effects
				(font
					(size 1 1)
					(thickness 0.15)
				)
			)
		)
		(property "License" "Apache-2.0"
			(at 377.35 358.998 0)
			(layer "F.Fab")
			(hide yes)
			(effects
				(font
					(size 1 1)
					(thickness 0.15)
				)
			)
		)
		(property "MPN" "RL1206FR-7W0R01L"
			(at 377.35 358.998 0)
			(layer "F.Fab")
			(hide yes)
			(effects
				(font
					(size 1 1)
					(thickness 0.15)
				)
			)
		)
		(property "Manufacturer" "YAGEO"
			(at 377.35 358.998 0)
			(layer "F.Fab")
			(hide yes)
			(effects
				(font
					(size 1 1)
					(thickness 0.15)
				)
			)
		)
		(property "Tolerance" "1%"
			(at 377.35 358.998 0)
			(layer "F.Fab")
			(hide yes)
			(effects
				(font
					(size 1 1)
					(thickness 0.15)
				)
			)
		)
		(property "Val" "0R01"
			(at 377.35 358.998 0)
			(layer "F.Fab")
			(hide yes)
			(effects
				(font
					(size 1 1)
					(thickness 0.15)
				)
			)
		)
		(sheetname "/Supply/")
		(sheetfile "supply.kicad_sch")
		(attr smd)
		(fp_line
			(start 0 0.9)
			(end 0.498 0.9)
			(stroke
				(width 0.15)
				(type solid)
			)
			(layer "F.SilkS")
		)
		(fp_line
			(start 0 0.9)
			(end -0.5 0.9)
			(stroke
				(width 0.15)
				(type solid)
			)
			(layer "F.SilkS")
		)
		(fp_line
			(start 0 -0.902)
			(end 0.498 -0.902)
			(stroke
				(width 0.15)
				(type solid)
			)
			(layer "F.SilkS")
		)
		(fp_line
			(start 0 -0.902)
			(end -0.5 -0.902)
			(stroke
				(width 0.15)
				(type solid)
			)
			(layer "F.SilkS")
		)
		(fp_rect
			(start -2.25 -1.05)
			(end 2.25 1.05)
			(stroke
				(width 0.05)
				(type solid)
			)
			(fill no)
			(layer "F.CrtYd")
		)
		(fp_line
			(start 1.6 -0.802)
			(end 1.6 0.8)
			(stroke
				(width 0.15)
				(type solid)
			)
			(layer "F.Fab")
		)
		(fp_line
			(start -1.601 0.8)
			(end 1.6 0.8)
			(stroke
				(width 0.15)
				(type solid)
			)
			(layer "F.Fab")
		)
		(fp_line
			(start -1.601 -0.802)
			(end 1.6 -0.802)
			(stroke
				(width 0.15)
				(type solid)
			)
			(layer "F.Fab")
		)
		(fp_line
			(start -1.601 -0.802)
			(end -1.601 0.8)
			(stroke
				(width 0.15)
				(type solid)
			)
			(layer "F.Fab")
		)
		(pad "1" smd roundrect
			(at -1.5 0 180)
			(size 1.2 1.8)
			(layers "F.Cu" "F.Mask" "F.Paste")
			(roundrect_rratio 0.15)
			(net 51 "/Supply/1V8_local")
			(pintype "passive")
		)
		(pad "2" smd roundrect
			(at 1.499 0 180)
			(size 1.2 1.8)
			(layers "F.Cu" "F.Mask" "F.Paste")
			(roundrect_rratio 0.15)
			(net 188 "+1V8")
			(pintype "passive")
		)
	)
	(footprint "antmicro-footprints:R_0402_1005Metric"
		(layer "F.Cu")
		(at 94.748501 126.719 -90)
		(descr "Resistor SMD 0402")
		(tags "resistor SMD 0402")
		(property "Reference" "R12"
			(at -1.122484 -0.772697 270)
			(layer "F.SilkS")
			(hide yes)
			(effects
				(font
					(size 0.7 0.7)
					(thickness 0.15)
				)
				(justify left bottom)
			)
		)
		(property "Value" "R_330R_0402"
			(at -1.011843 1.772047 270)
			(layer "F.Fab")
			(effects
				(font
					(size 0.7 0.7)
					(thickness 0.15)
				)
				(justify left bottom)
			)
		)
		(property "Datasheet" "https://www.bourns.com/docs/product-datasheets/cr.pdf"
			(at 0 0 270)
			(layer "F.Fab")
			(hide yes)
			(effects
				(font
					(size 1.27 1.27)
					(thickness 0.15)
				)
			)
		)
		(property "Author" "Antmicro"
			(at -31.970499 221.467501 0)
			(layer "F.Fab")
			(hide yes)
			(effects
				(font
					(size 1 1)
					(thickness 0.15)
				)
			)
		)
		(property "License" "Apache-2.0"
			(at -31.970499 221.467501 0)
			(layer "F.Fab")
			(hide yes)
			(effects
				(font
					(size 1 1)
					(thickness 0.15)
				)
			)
		)
		(property "MPN" "CR0402-FX-3300GLF"
			(at -31.970499 221.467501 0)
			(layer "F.Fab")
			(hide yes)
			(effects
				(font
					(size 1 1)
					(thickness 0.15)
				)
			)
		)
		(property "Manufacturer" "Bourns"
			(at -31.970499 221.467501 0)
			(layer "F.Fab")
			(hide yes)
			(effects
				(font
					(size 1 1)
					(thickness 0.15)
				)
			)
		)
		(property "Tolerance" "1%"
			(at -31.970499 221.467501 0)
			(layer "F.Fab")
			(hide yes)
			(effects
				(font
					(size 1 1)
					(thickness 0.15)
				)
			)
		)
		(property "Val" "330R"
			(at -31.970499 221.467501 0)
			(layer "F.Fab")
			(hide yes)
			(effects
				(font
					(size 1 1)
					(thickness 0.15)
				)
			)
		)
		(sheetname "/FPGA Config/")
		(sheetfile "fpga-config.kicad_sch")
		(attr smd)
		(fp_rect
			(start -0.93 -0.47)
			(end 0.93 0.47)
			(stroke
				(width 0.05)
				(type solid)
			)
			(fill no)
			(layer "F.CrtYd")
		)
		(fp_rect
			(start -0.5 -0.25)
			(end 0.5 0.25)
			(stroke
				(width 0.15)
				(type solid)
			)
			(fill no)
			(layer "F.Fab")
		)
		(pad "1" smd roundrect
			(at -0.485 0 270)
			(size 0.59 0.64)
			(layers "F.Cu" "F.Mask" "F.Paste")
			(roundrect_rratio 0.25)
			(net 305 "Net-(D2-Pad2)")
			(pintype "passive")
		)
		(pad "2" smd roundrect
			(at 0.485 0 270)
			(size 0.59 0.64)
			(layers "F.Cu" "F.Mask" "F.Paste")
			(roundrect_rratio 0.25)
			(net 351 "Net-(Q2-D)")
			(pintype "passive")
		)
	)
	(footprint "antmicro-footprints:NetTie-2_SMD_Pad0.127mm"
		(layer "F.Cu")
		(at 199.876501 159.699)
		(descr "Net tie, 2 pin, 0.127mm  SMD pads")
		(tags "net tie")
		(property "Reference" "NT7"
			(at -0.128 -1.345 0)
			(layer "F.SilkS")
			(hide yes)
			(effects
				(font
					(size 0.7 0.7)
					(thickness 0.15)
				)
				(justify left bottom)
			)
		)
		(property "Value" "Net-Tie_P0.127mm"
			(at 0 1.199 0)
			(layer "F.Fab")
			(effects
				(font
					(size 0.7 0.7)
					(thickness 0.15)
				)
				(justify left bottom)
			)
		)
		(property "Author" "Antmicro"
			(at 0 0 0)
			(layer "F.Fab")
			(hide yes)
			(effects
				(font
					(size 1 1)
					(thickness 0.15)
				)
			)
		)
		(property "License" "Apache-2.0"
			(at 0 0 0)
			(layer "F.Fab")
			(hide yes)
			(effects
				(font
					(size 1 1)
					(thickness 0.15)
				)
			)
		)
		(property "MPN" ""
			(at 0 0 0)
			(layer "F.Fab")
			(hide yes)
			(effects
				(font
					(size 1 1)
					(thickness 0.15)
				)
			)
		)
		(property "Manufacturer" ""
			(at 0 0 0)
			(layer "F.Fab")
			(hide yes)
			(effects
				(font
					(size 1 1)
					(thickness 0.15)
				)
			)
		)
		(property ki_fp_filters "Net*Tie*")
		(sheetname "/Supply/")
		(sheetfile "supply.kicad_sch")
		(attr smd exclude_from_pos_files exclude_from_bom)
		(net_tie_pad_groups "1, 2")
		(fp_poly
			(pts
				(xy -0.0635 -0.0635) (xy 0.0625 -0.0635) (xy 0.0625 0.0635) (xy -0.0635 0.0635)
			)
			(stroke
				(width 0)
				(type solid)
			)
			(fill yes)
			(layer "F.Cu")
		)
		(pad "1" smd roundrect
			(at -0.127 0 180)
			(size 0.127 0.127)
			(layers "F.Cu")
			(roundrect_rratio 0.5)
			(chamfer_ratio 0)
			(chamfer top_left bottom_left)
			(net 142 "/Supply/1V1_SEN_+")
			(pinfunction "1")
			(pintype "passive")
		)
		(pad "2" smd roundrect
			(at 0.126 0)
			(size 0.127 0.127)
			(layers "F.Cu")
			(roundrect_rratio 0.5)
			(chamfer_ratio 0)
			(chamfer top_left bottom_left)
			(net 53 "/Supply/1V1_local")
			(pinfunction "2")
			(pintype "passive")
		)
	)
	(footprint "antmicro-footprints:R_0603_1608Metric"
		(layer "F.Cu")
		(at 166.100501 197.114501 180)
		(descr "Resistor SMD 0603")
		(tags "resistor SMD 0603")
		(property "Reference" "R188"
			(at 1.550501 0.9 180)
			(layer "F.SilkS")
			(effects
				(font
					(size 0.7 0.7)
					(thickness 0.15)
				)
				(justify left bottom)
			)
		)
		(property "Value" "R_0R_22.4A_0603"
			(at 0 1.6 180)
			(layer "F.Fab")
			(effects
				(font
					(size 0.7 0.7)
					(thickness 0.15)
				)
				(justify left bottom)
			)
		)
		(property "Datasheet" "https://fscdn.rohm.com/en/products/databook/datasheet/passive/resistor/chip_resistor/pmr-jpw-e.pdf"
			(at 0 0 180)
			(layer "F.Fab")
			(hide yes)
			(effects
				(font
					(size 1.27 1.27)
					(thickness 0.15)
				)
			)
		)
		(property "Author" "Antmicro"
			(at 332.201002 394.229002 0)
			(layer "F.Fab")
			(hide yes)
			(effects
				(font
					(size 1 1)
					(thickness 0.15)
				)
			)
		)
		(property "License" "Apache-2.0"
			(at 332.201002 394.229002 0)
			(layer "F.Fab")
			(hide yes)
			(effects
				(font
					(size 1 1)
					(thickness 0.15)
				)
			)
		)
		(property "MPN" "PMR03EZPJ000"
			(at 332.201002 394.229002 0)
			(layer "F.Fab")
			(hide yes)
			(effects
				(font
					(size 1 1)
					(thickness 0.15)
				)
			)
		)
		(property "Manufacturer" "ROHM Semiconductor"
			(at 332.201002 394.229002 0)
			(layer "F.Fab")
			(hide yes)
			(effects
				(font
					(size 1 1)
					(thickness 0.15)
				)
			)
		)
		(property "Max. Curr." "22.4A"
			(at 332.201002 394.229002 0)
			(layer "F.Fab")
			(hide yes)
			(effects
				(font
					(size 1 1)
					(thickness 0.15)
				)
			)
		)
		(property "Val" "0R"
			(at 332.201002 394.229002 0)
			(layer "F.Fab")
			(hide yes)
			(effects
				(font
					(size 1 1)
					(thickness 0.15)
				)
			)
		)
		(sheetname "/Supply/")
		(sheetfile "supply.kicad_sch")
		(attr smd)
		(fp_line
			(start -0.3 0.3)
			(end 0.3 0.3)
			(stroke
				(width 0.15)
				(type solid)
			)
			(layer "F.SilkS")
		)
		(fp_line
			(start -0.3 -0.3)
			(end 0.3 -0.3)
			(stroke
				(width 0.15)
				(type solid)
			)
			(layer "F.SilkS")
		)
		(fp_rect
			(start -1.25 -0.7)
			(end 1.25 0.7)
			(stroke
				(width 0.05)
				(type solid)
			)
			(fill no)
			(layer "F.CrtYd")
		)
		(fp_rect
			(start -0.8 -0.4)
			(end 0.8 0.4)
			(stroke
				(width 0.15)
				(type solid)
			)
			(fill no)
			(layer "F.Fab")
		)
		(pad "1" smd roundrect
			(at -0.7 0 180)
			(size 0.6 0.8)
			(layers "F.Cu" "F.Mask" "F.Paste")
			(roundrect_rratio 0.2)
			(net 78 "/Supply/1V0_REG")
			(pintype "passive")
		)
		(pad "2" smd roundrect
			(at 0.7 0 180)
			(size 0.6 0.8)
			(layers "F.Cu" "F.Mask" "F.Paste")
			(roundrect_rratio 0.2)
			(net 227 "+1V0")
			(pintype "passive")
		)
	)
	(footprint "antmicro-footprints:C_0402_1005Metric"
		(layer "F.Cu")
		(at 83.649 150.634 90)
		(descr "Capacitor SMD 0402")
		(tags "capacitor SMD 0402")
		(property "Reference" "C113"
			(at 0 -0.699 90)
			(layer "F.SilkS")
			(hide yes)
			(effects
				(font
					(size 0.7 0.7)
					(thickness 0.15)
				)
				(justify left bottom)
			)
		)
		(property "Value" "C_10u_6.3V_0402"
			(at -1.022927 2.155213 90)
			(layer "F.Fab")
			(effects
				(font
					(size 0.7 0.7)
					(thickness 0.15)
				)
				(justify left bottom)
			)
		)
		(property "Datasheet" "https://www.murata.com/products/productdetail?partno=GRM155R60J106ME15%23"
			(at 0 0 90)
			(layer "F.Fab")
			(hide yes)
			(effects
				(font
					(size 1.27 1.27)
					(thickness 0.15)
				)
			)
		)
		(property "Author" "Antmicro"
			(at 234.283 66.985 0)
			(layer "F.Fab")
			(hide yes)
			(effects
				(font
					(size 1 1)
					(thickness 0.15)
				)
			)
		)
		(property "Dielectric" "X5R"
			(at 234.283 66.985 0)
			(layer "F.Fab")
			(hide yes)
			(effects
				(font
					(size 1 1)
					(thickness 0.15)
				)
			)
		)
		(property "License" "Apache-2.0"
			(at 234.283 66.985 0)
			(layer "F.Fab")
			(hide yes)
			(effects
				(font
					(size 1 1)
					(thickness 0.15)
				)
			)
		)
		(property "MPN" "GRM155R60J106ME15D"
			(at 234.283 66.985 0)
			(layer "F.Fab")
			(hide yes)
			(effects
				(font
					(size 1 1)
					(thickness 0.15)
				)
			)
		)
		(property "Manufacturer" "Murata"
			(at 234.283 66.985 0)
			(layer "F.Fab")
			(hide yes)
			(effects
				(font
					(size 1 1)
					(thickness 0.15)
				)
			)
		)
		(property "Val" "10u"
			(at 234.283 66.985 0)
			(layer "F.Fab")
			(hide yes)
			(effects
				(font
					(size 1 1)
					(thickness 0.15)
				)
			)
		)
		(property "Voltage" "6.3V"
			(at 234.283 66.985 0)
			(layer "F.Fab")
			(hide yes)
			(effects
				(font
					(size 1 1)
					(thickness 0.15)
				)
			)
		)
		(sheetname "/Debug FTDI/")
		(sheetfile "debug-ftdi.kicad_sch")
		(attr smd)
		(fp_rect
			(start -0.9659 -0.481258)
			(end 0.9649 0.458742)
			(stroke
				(width 0.05)
				(type solid)
			)
			(fill no)
			(layer "F.CrtYd")
		)
		(fp_line
			(start 0.499 -0.25)
			(end 0.499 0.248)
			(stroke
				(width 0.15)
				(type solid)
			)
			(layer "F.Fab")
		)
		(fp_line
			(start -0.499 -0.25)
			(end 0.499 -0.25)
			(stroke
				(width 0.15)
				(type solid)
			)
			(layer "F.Fab")
		)
		(fp_line
			(start 0.499 0.248)
			(end -0.499 0.248)
			(stroke
				(width 0.15)
				(type solid)
			)
			(layer "F.Fab")
		)
		(fp_line
			(start -0.499 0.248)
			(end -0.499 -0.25)
			(stroke
				(width 0.15)
				(type solid)
			)
			(layer "F.Fab")
		)
		(pad "1" smd roundrect
			(at -0.484 0 90)
			(size 0.59 0.64)
			(layers "F.Cu" "F.Mask" "F.Paste")
			(roundrect_rratio 0.25)
			(net 1 "GND")
			(pintype "passive")
		)
		(pad "2" smd roundrect
			(at 0.484 0 90)
			(size 0.59 0.64)
			(layers "F.Cu" "F.Mask" "F.Paste")
			(roundrect_rratio 0.25)
			(net 6 "/Debug FTDI/FTDI_3V3")
			(pintype "passive")
		)
	)
	(footprint "antmicro-footprints:R_0402_1005Metric"
		(layer "F.Cu")
		(at 202.881001 170.222 -90)
		(descr "Resistor SMD 0402")
		(tags "resistor SMD 0402")
		(property "Reference" "R168"
			(at 3.778 -0.368999 270)
			(layer "F.SilkS")
			(effects
				(font
					(size 0.7 0.7)
					(thickness 0.15)
				)
				(justify left bottom)
			)
		)
		(property "Value" "R_0R_0402"
			(at -1.011843 1.772047 270)
			(layer "F.Fab")
			(effects
				(font
					(size 0.7 0.7)
					(thickness 0.15)
				)
				(justify left bottom)
			)
		)
		(property "Datasheet" "https://industrial.panasonic.com/cdbs/www-data/pdf/RDA0000/AOA0000C301.pdf"
			(at 0 0 270)
			(layer "F.Fab")
			(hide yes)
			(effects
				(font
					(size 1.27 1.27)
					(thickness 0.15)
				)
			)
		)
		(property "Author" "Antmicro"
			(at 32.659001 373.103001 0)
			(layer "F.Fab")
			(hide yes)
			(effects
				(font
					(size 1 1)
					(thickness 0.15)
				)
			)
		)
		(property "Current" "1A"
			(at 32.659001 373.103001 0)
			(layer "F.Fab")
			(hide yes)
			(effects
				(font
					(size 1 1)
					(thickness 0.15)
				)
			)
		)
		(property "License" "Apache-2.0"
			(at 32.659001 373.103001 0)
			(layer "F.Fab")
			(hide yes)
			(effects
				(font
					(size 1 1)
					(thickness 0.15)
				)
			)
		)
		(property "MPN" "ERJ2GE0R00X"
			(at 32.659001 373.103001 0)
			(layer "F.Fab")
			(hide yes)
			(effects
				(font
					(size 1 1)
					(thickness 0.15)
				)
			)
		)
		(property "Manufacturer" "Panasonic"
			(at 32.659001 373.103001 0)
			(layer "F.Fab")
			(hide yes)
			(effects
				(font
					(size 1 1)
					(thickness 0.15)
				)
			)
		)
		(property "Tolerance" ""
			(at 32.659001 373.103001 0)
			(layer "F.Fab")
			(hide yes)
			(effects
				(font
					(size 1 1)
					(thickness 0.15)
				)
			)
		)
		(property "Val" "0R"
			(at 32.659001 373.103001 0)
			(layer "F.Fab")
			(hide yes)
			(effects
				(font
					(size 1 1)
					(thickness 0.15)
				)
			)
		)
		(sheetname "/Supply/")
		(sheetfile "supply.kicad_sch")
		(attr smd)
		(fp_rect
			(start -0.93 -0.47)
			(end 0.93 0.47)
			(stroke
				(width 0.05)
				(type solid)
			)
			(fill no)
			(layer "F.CrtYd")
		)
		(fp_rect
			(start -0.5 -0.25)
			(end 0.5 0.25)
			(stroke
				(width 0.15)
				(type solid)
			)
			(fill no)
			(layer "F.Fab")
		)
		(pad "1" smd roundrect
			(at -0.485 0 270)
			(size 0.59 0.64)
			(layers "F.Cu" "F.Mask" "F.Paste")
			(roundrect_rratio 0.25)
			(net 218 "/Supply/FB8")
			(pintype "passive")
		)
		(pad "2" smd roundrect
			(at 0.485 0 270)
			(size 0.59 0.64)
			(layers "F.Cu" "F.Mask" "F.Paste")
			(roundrect_rratio 0.25)
			(net 56 "/Supply/1V2_local")
			(pintype "passive")
		)
	)
)
